FILE_TYPE = MACRO_DRAWING;
SET COLOR_WIRE YELLOW;
SET COLOR_PROP ORANGE;
SET COLOR_DOT WHITE;
SET COLOR_ARC YELLOW;
SET COLOR_BODY GREEN;
SET COLOR_NOTE PURPLE;
SET PROP_DISPLAY VALUE;
SET PAGE_NUMBER P116;
FORCEADD QUANTA_TITLE_BLOCK_C..1
(0 0);
FORCEPROP 1 LAST CUSTOM_TXT_CDS <NAME_2>
J 0
(-3175 50);
FORCEPROP 1 LAST CUSTOM_TXT_CDS <NAME_1>
J 0
(-3175 175);
FORCEPROP 1 LAST CUSTOM_TXT_CDS <Q_NUMBER>
J 0
(-1403 103);
DISPLAY 1.212766 (-1403 103);
FORCEPROP 1 LAST CUSTOM_TXT_CDS <Q_PROJ>
J 0
(-2382 102);
DISPLAY 1.212766 (-2382 102);
FORCEPROP 1 LAST CUSTOM_TXT_CDS <Q_REV>
J 0
(-184 103);
DISPLAY 1.212766 (-184 103);
FORCEPROP 1 LAST CUSTOM_TXT_CDS <CON_LAST_MODIFIED>
J 0
(-1885 15);
DISPLAY 0.978723 (-1885 15);
FORCEPROP 1 LAST CUSTOM_TXT_CDS <CON_PAGE_NUM> OF <CON_TOTAL_PAGES>
J 0
(-446 18);
DISPLAY 0.978723 (-446 18);
FORCEPROP 1 LAST Q_TITLE PCIE X16 SLOT3
J 0
(-9366 26);
DISPLAY 2.446809 (-9366 26);
PAINT GREEN (-9366 26);
FORCEPROP 1 LAST Q_DEPT BU9
J 1
(-3763 49);
DISPLAY 1.957447 (-3763 49);
PAINT GREEN (-3763 49);
FORCEPROP 2 LAST CDS_LIB pure_quanta
J 0
(0 0);
DISPLAY INVISIBLE (0 0);
FORCEPROP 1 LAST CDS_LMAN_SYM_OUTLINE -9475,6775,100,-125
J 0
(0 0);
DISPLAY 0.468085 (0 0);
PAINT GREEN (0 0);
DISPLAY INVISIBLE (0 0);
FORCEPROP 2 LAST PAGE_BORDER TRUE
J 0
(-7890 5250);
DISPLAY 0.638298 (-7890 5250);
PAINT PINK (-7890 5250);
DISPLAY INVISIBLE (-7890 5250);
FORCEPROP 1 LAST COMMENT_BODY TRUE
J 0
(12 -13);
DISPLAY 0.978723 (12 -13);
PAINT GREEN (12 -13);
DISPLAY INVISIBLE (12 -13);
FORCEPROP 2 LAST CDS_XR_PAGE_TITLE CR-116 : @T6G_MB_LIB.T6G(SCH_1):PAGE116
J 0
(-7890 5250);
DISPLAY 0.638298 (-7890 5250);
PAINT PINK (-7890 5250);
DISPLAY INVISIBLE (-7890 5250);
FORCEPROP 2 LAST CUSTOM_TXT_CDS <XR_PAGE_TITLE>
J 0
(-7890 5250);
DISPLAY 0.638298 (-7890 5250);
PAINT PINK (-7890 5250);
DISPLAY INVISIBLE (-7890 5250);
FORCEPROP 0 LAST CDS_CON_LAST_MODIFIED Wed Mar 09 16:48:54 2022
J 0
(-1885 15);
DISPLAY INVISIBLE (-1885 15);
QUIT
